# T6G (Grand Teton) — schematic parts with pin connectivity, parts 6678–6830 of 8303; source: Cadence DE-HDL packaged netlist (pstxprt.dat, pstxnet.dat, pstchip.dat)

R3190  Q_RES  4.7K 1% CHIP  pkg 0402LF  page 139 : 1 = P3V3_AUX ; 2 = OCP_V3_2_PWRBRK_BUFF_N
R3191  Q_RES  33.2 1% CHIP  pkg 0402LF  page 139 : 1 = OCP_V3_2_PWRBRK_BUFF_N ; 2 = OCP_V3_2_PWRBRK_N
R3192  Q_RES  4.7K 1% EMPTY  pkg 0402LF  page 139 : 1 = P3V3_AUX ; 2 = IRQ_LVC3_V3_2_WAKE_BUF_N
R3193  Q_RES  33.2 1% CHIP  pkg 0402LF  page 139 : 1 = IRQ_LVC3_V3_2_WAKE_BUF_N ; 2 = IRQ_OCP_V3_2_WAKE_BUF_N
R3194  Q_RES  0 5% CHIP  pkg 0402LF  page 55 : 1 = CLK_100M_CPU1_CLK02_R_DP ; 2 = CLK_100M_CPU1_CLK02_DP
R3195  Q_RES  0 5% CHIP  pkg 0402LF  page 55 : 1 = CLK_100M_CPU1_CLK02_R_DN ; 2 = CLK_100M_CPU1_CLK02_DN
R3196  Q_RES  0 5% CHIP  pkg 0402LF  page 55 : 1 = CLK_100M_CPU1_CLK03_R_DP ; 2 = CLK_100M_CPU1_CLK03_DP
R3197  Q_RES  0 5% CHIP  pkg 0402LF  page 55 : 1 = CLK_100M_CPU1_CLK03_R_DN ; 2 = CLK_100M_CPU1_CLK03_DN
R3198  Q_RES  0 5% CHIP  pkg 0402LF  page 55 : 1 = CLK_100M_CPU1_CLK04_R_DP ; 2 = CLK_100M_CPU1_CLK04_DP
R3199  Q_RES  0 5% CHIP  pkg 0402LF  page 55 : 1 = CLK_100M_CPU1_CLK04_R_DN ; 2 = CLK_100M_CPU1_CLK04_DN
R3200  Q_RES  0 5% CHIP  pkg 0402LF  page 55 : 1 = CLK_100M_CPU1_CLK05_R_DP ; 2 = CLK_100M_CPU1_CLK05_DP
R3201  Q_RES  0 5% CHIP  pkg 0402LF  page 55 : 1 = CLK_100M_CPU1_CLK05_R_DN ; 2 = CLK_100M_CPU1_CLK05_DN
R3203  Q_RES  33.2 1% CHIP  pkg 0402LF  page 138 : 1 = OCP_V3_2_AUX_PWR_EN ; 2 = OCP_V3_2_AUX_PWR_EN_R1
R3205  Q_RES  0 5% CHIP  pkg 0402LF  page 138 : 1 = FB_BMC_ISOLATE_R2 ; 2 = FB_BMC_ISOLATE1
R3206  Q_RES  0 5% EMPTY  pkg 0402LF  page 138 : 1 = FM_NCSI_OCP_V3_2_R_OE ; 2 = FB_BMC_ISOLATE1
R3207  Q_RES  100K 1% CHIP  pkg 0402LF  page 138 : 1 = FB_BMC_ISOLATE1 ; 2 = GND
R3208  Q_RES  100 1% CHIP  pkg 0402LF  page 138 : 1 = OCP_V3_2_ISO_BIF0_EN ; 2 = GND
R3209  Q_RES  22 1% EMPTY  pkg 0402LF  page 138 : 1 = OCP_V3_2_RBT_ARB_IN_R ; 2 = OCP_V3_2_RBT_ARB_IN
R3210  Q_RES  22 1% EMPTY  pkg 0402LF  page 138 : 1 = NCSI_BMC_CRS_DV_R1 ; 2 = RMII_OCP_BMC_CRSDV
R3211  Q_RES  22 1% EMPTY  pkg 0402LF  page 138 : 1 = NCSI_BMC_RXD0_R1 ; 2 = RMII_OCP_BMC_RXD_0
R3212  Q_RES  22 1% EMPTY  pkg 0402LF  page 138 : 1 = NCSI_BMC_RXD1_R1 ; 2 = RMII_OCP_BMC_RXD_1
R3213  Q_RES  0 5% EMPTY  pkg 0402LF  page 138 : 1 = NCSI_BMC_TX_EN_R1 ; 2 = RMII_BMC_OCP_TX_EN
R3214  Q_RES  0 5% EMPTY  pkg 0402LF  page 138 : 1 = NCSI_BMC_TXD0_R1 ; 2 = RMII_BMC_OCP_TXD_0
R3215  Q_RES  0 5% EMPTY  pkg 0402LF  page 138 : 1 = NCSI_BMC_TXD1_R1 ; 2 = RMII_BMC_OCP_TXD_1
R3216  Q_RES  100 1% CHIP  pkg 0402LF  page 138 : 1 = OCP_V3_2_ISO_BIF1_EN ; 2 = GND
R3217  Q_RES  100 1% CHIP  pkg 0402LF  page 138 : 1 = OCP_V3_2_ISO_BIF2_EN ; 2 = GND
R3226  Q_RES  2.2K 5% EMPTY  pkg 0402LF  page 151 : 1 = SMB_1_BMC_GPU_SCL ; 2 = P3V3_AUX
R3227  Q_RES  2.2K 5% EMPTY  pkg 0402LF  page 151 : 1 = SMB_1_BMC_GPU_SDA ; 2 = P3V3_AUX
R3228  Q_RES  200 1% CHIP  pkg 0402LF  page 137 : 1 = SMB_OCP_V3_2_3V3AUX_BUF_R_SCL ; 2 = SMB_OCP_V3_2_3V3AUX_BUF_SCL
R3229  Q_RES  200 1% CHIP  pkg 0402LF  page 137 : 1 = SMB_OCP_V3_2_3V3AUX_BUF_R_SDA ; 2 = SMB_OCP_V3_2_3V3AUX_BUF_SDA
R3231  Q_RES  33.2 1% CHIP  pkg 0402LF  page 132 : 1 = OCP_SFF_AUX_PWR_EN ; 2 = OCP_SFF_AUX_PWR_EN_R2
R3232  Q_RES  100K 1% CHIP  pkg 0402LF  page 132 : 1 = RST_HP_OCP_SFF_R_N ; 2 = GND
R3233  Q_RES  0 5% CHIP  pkg 0402LF  page 132 : 1 = RST_HP_OCP_SFF_R_N ; 2 = RST_SMB_OCP_SFF_N
R3234  Q_RES  33.2 1% CHIP  pkg 0402LF  page 139 : 1 = OCP_V3_2_AUX_PWR_EN ; 2 = OCP_V3_2_AUX_PWR_EN_R3
R3235  Q_RES  100K 1% CHIP  pkg 0402LF  page 139 : 1 = RST_HP_OCP_V3_2_R_N ; 2 = GND
R3236  Q_RES  0 5% CHIP  pkg 0402LF  page 139 : 1 = RST_HP_OCP_V3_2_R_N ; 2 = RST_SMB_OCP_V3_2_N
R3237  Q_RES  0 5% CHIP  pkg 0402LF  page 132 : 1 = OCP_SFF_RBT_ARB_OUT ; 2 = OCP_SFF_RBT_ARB_IN_R
R3238  Q_RES  33.2 1% CHIP  pkg 0402LF  page 150 : 1 = SMB_OCP_SFF_3V3AUX_SCL ; 2 = SMB_OCP_SFF_3V3AUX_SCL_R0
R3239  Q_RES  33.2 1% CHIP  pkg 0402LF  page 150 : 1 = SMB_OCP_SFF_3V3AUX_SDA ; 2 = SMB_OCP_SFF_3V3AUX_SDA_R0
R3240  Q_RES  2.2K 5% EMPTY  pkg 0402LF  page 151 : 1 = SMB_OCP_SFF_3V3AUX_SCL ; 2 = P3V3_AUX
R3241  Q_RES  2.2K 5% EMPTY  pkg 0402LF  page 151 : 1 = SMB_OCP_SFF_3V3AUX_SDA ; 2 = P3V3_AUX
R3242  Q_RES  2.2K 5% EMPTY  pkg 0402LF  page 151 : 1 = SMB_OCP_V3_2_3V3AUX_SCL ; 2 = P3V3_AUX
R3243  Q_RES  2.2K 5% EMPTY  pkg 0402LF  page 151 : 1 = SMB_OCP_V3_2_3V3AUX_SDA ; 2 = P3V3_AUX
R3244  Q_RES  0 5% CHIP  pkg 0402LF  page 138 : 1 = OCP_V3_2_RBT_ARB_OUT ; 2 = OCP_V3_2_RBT_ARB_IN_R
R3254  Q_RES  0 5% EMPTY  pkg 0402LF  page 150 : 1 = TP_PCIE_TXP<3> ; 2 = LED_HDD_ACTIVITY_B_N
R3263  Q_RES  0 5% EMPTY  pkg 0402LF  page 247 : 1 = HP_LVC3_OCP_V3_1_R_EN ; 2 = P3V3_OCP_SFF_EN_R
R3264  Q_RES  0 5% EMPTY  pkg 0402LF  page 247 : 1 = HP_LVC3_OCP_V3_2_R_EN ; 2 = P3V3_OCP_V3_2_EN_R
R3265  Q_RES  4.7K 1% EMPTY  pkg 0402LF  page 111 : 1 = CLK_GEN2_GPU_FPGA_OE_OR_N ; 2 = GND
R3266  Q_RES  4.7K 1% CHIP  pkg 0402LF  page 111 : 1 = P3V3_AUX ; 2 = FM_P2E_MODE
R3267  Q_RES  68K 1% EMPTY  pkg 0402LF  page 111 : 1 = FM_P2E_FGB ; 2 = GND
R3268  Q_RES  68K 1% EMPTY  pkg 0402LF  page 111 : 1 = FM_P2E_EQA1 ; 2 = GND
R3269  Q_RES  1K 1% EMPTY  pkg 0402LF  page 111 : 1 = P3V3_AUX ; 2 = FM_P2E_FGB
R3270  Q_RES  1K 1% EMPTY  pkg 0402LF  page 111 : 1 = FM_P2E_FGB ; 2 = GND
R3271  Q_RES  1K 1% EMPTY  pkg 0402LF  page 111 : 1 = P3V3_AUX ; 2 = FM_P2E_EQA1
R3272  Q_RES  1K 1% EMPTY  pkg 0402LF  page 111 : 1 = FM_P2E_EQA1 ; 2 = GND
R3273  Q_RES  68K 1% EMPTY  pkg 0402LF  page 111 : 1 = FM_P2E_FGA ; 2 = GND
R3274  Q_RES  68K 1% EMPTY  pkg 0402LF  page 111 : 1 = FM_P2E_EQA0 ; 2 = GND
R3275  Q_RES  1K 1% EMPTY  pkg 0402LF  page 111 : 1 = P3V3_AUX ; 2 = FM_P2E_FGA
R3276  Q_RES  1K 1% EMPTY  pkg 0402LF  page 111 : 1 = FM_P2E_FGA ; 2 = GND
R3277  Q_RES  1K 1% EMPTY  pkg 0402LF  page 111 : 1 = P3V3_AUX ; 2 = FM_P2E_EQA0
R3278  Q_RES  1K 1% CHIP  pkg 0402LF  page 111 : 1 = FM_P2E_EQA0 ; 2 = GND
R3279  Q_RES  68K 1% EMPTY  pkg 0402LF  page 111 : 1 = FM_P2E_EQB1 ; 2 = GND
R3280  Q_RES  1K 1% EMPTY  pkg 0402LF  page 111 : 1 = P3V3_AUX ; 2 = FM_P2E_EQB1
R3281  Q_RES  1K 1% EMPTY  pkg 0402LF  page 111 : 1 = FM_P2E_EQB1 ; 2 = GND
R3282  Q_RES  68K 1% EMPTY  pkg 0402LF  page 111 : 1 = FM_P2E_EQB0 ; 2 = GND
R3283  Q_RES  1K 1% EMPTY  pkg 0402LF  page 111 : 1 = P3V3_AUX ; 2 = FM_P2E_EQB0
R3284  Q_RES  1K 1% CHIP  pkg 0402LF  page 111 : 1 = FM_P2E_EQB0 ; 2 = GND
R3285  Q_RES  68K 1% EMPTY  pkg 0402LF  page 111 : 1 = FM_P2E_SWB ; 2 = GND
R3286  Q_RES  1K 1% EMPTY  pkg 0402LF  page 111 : 1 = P3V3_AUX ; 2 = FM_P2E_SWB
R3287  Q_RES  1K 1% EMPTY  pkg 0402LF  page 111 : 1 = FM_P2E_SWB ; 2 = GND
R3288  Q_RES  68K 1% EMPTY  pkg 0402LF  page 111 : 1 = FM_P2E_SWA ; 2 = GND
R3289  Q_RES  1K 1% EMPTY  pkg 0402LF  page 111 : 1 = P3V3_AUX ; 2 = FM_P2E_SWA
R3290  Q_RES  1K 1% EMPTY  pkg 0402LF  page 111 : 1 = FM_P2E_SWA ; 2 = GND
R3291  Q_RES  4.7K 1% EMPTY  pkg 0402LF  page 111 : 1 = PU_TEST ; 2 = GND
R3292  Q_RES  4.7K 1% CHIP  pkg 0402LF  page 111 : 1 = P3V3_AUX ; 2 = CLK_GEN2_GPU_FPGA_OE_OR_N
R3293  Q_RES  4.7K 1% EMPTY  pkg 0402LF  page 111 : 1 = FM_P2E_MODE ; 2 = GND
R3294  Q_RES  0 5% CHIP  pkg 0402LF  page 144 : 1 = LED_M2_SSD_0_ACT_N ; 2 = LED_HDD_ACTIVITY_N
R3295  Q_RES  4.7K 1% CHIP  pkg 0402LF  page 144 : 1 = P3V3_M2_0 ; 2 = LED_HDD_ACTIVITY_N
R3296  Q_RES  4.7K 1% CHIP  pkg 0402LF  page 144 : 1 = P3V3_AUX ; 2 = HDD_ACTIVITY_BUF
R3297  Q_RES  10K 1% CHIP  pkg 0402LF  page 144 : 1 = LED_HDD_ACTIVITY_B_N ; 2 = GND
R3298  Q_RES  10K 1% CHIP  pkg 0402LF  page 144 : 1 = P3V3_AUX ; 2 = HDD_ACTIVITY_BUF_N
R3301  Q_RES  33.2 1% CHIP  pkg 0402LF  page 144 : 1 = M2_0_PEWAKE_R_N ; 2 = M2_0_PEWAKE_N
R3303  Q_RES  0 5% CHIP  pkg 0402LF  page 143 : 1 = OCP_SFF_PRSNT_ALL_R_N ; 2 = OCP_SFF_PRSNT_ALL_R1_N
R3304  Q_RES  0 5% CHIP  pkg 0402LF  page 143 : 1 = OCP_SFF_PRSNT_ALL_R_N ; 2 = OCP_SFF_PRSNT_ALL_R3_N
R3305  Q_RES  0 5% CHIP  pkg 0402LF  page 143 : 1 = OCP_SFF_RBT_ARB_IN_MUX1 ; 2 = OCP_SFF_RBT_ARB_IN_MUX1_R
R3306  Q_RES  0 5% CHIP  pkg 0402LF  page 143 : 1 = OCP_V3_2_PRSNT_ALL_R_N ; 2 = OCP_V3_2_PRSNT_ALL_R3_N
R3307  Q_RES  0 5% CHIP  pkg 0402LF  page 143 : 1 = OCP_SFF_RBT_ARB_IN_MUX2 ; 2 = OCP_SFF_RBT_ARB_IN_MUX2_R
R3308  Q_RES  0 5% CHIP  pkg 0402LF  page 143 : 1 = OCP_V3_2_PRSNT_ALL_R_N ; 2 = OCP_V3_2_PRSNT_ALL_R1_N
R3315  Q_RES  33.2 1% CHIP  pkg 0402LF  page 130 : 1 = GPU_FPGA_RST_R1_BUF_N ; 2 = GPU_FPGA_RST_R_BUF_N
R3317  Q_RES  4.7K 5% EMPTY  pkg 0402LF  page 130 : 1 = P3V3_AUX ; 2 = GPU_FPGA_RST_R1_BUF_N
R3318  Q_RES  100K 1% EMPTY  pkg 0402LF  page 127 : 1 = P3V3_AUX ; 2 = GPU_FPGA_READY
R3320  Q_RES  4.7K 5% CHIP  pkg 0402LF  page 127 : 1 = P3V3_AUX ; 2 = GPU_FPGA_READY_N
R3321  Q_RES  100K 1% CHIP  pkg 0402LF  page 127 : 1 = P3V3_AUX ; 2 = GPU_FPGA_READY_ISO
R3322  Q_RES  1K 1% CHIP  pkg 0402LF  page 233 : 1 = P3V3_AUX ; 2 = CLK_GEN2_GPU_FPGA_OE_R2_N
R3324  Q_RES  33.2 1% CHIP  pkg 0402LF  page 81 : 1 = GPU_FPGA_READY_ISO_R ; 2 = GPU_FPGA_READY_ISO
R3326  Q_RES  0 5% CHIP  pkg 0402LF  page 233 : 1 = GPU_FPGA_READY_N ; 2 = GPU_FPGA_READY_R_N
R3327  Q_RES  0 5% CHIP  pkg 0402LF  page 233 : 1 = CLK_GEN2_GPU_FPGA_OE_N ; 2 = CLK_GEN2_GPU_FPGA_OE_R2_N
R3335  Q_RES  0 5% CHIP  pkg 0402LF  page 233 : 1 = CLK_100M_BMC_RC_DP_R ; 2 = CLK_100M_BMC_RC_DP
R3336  Q_RES  0 5% CHIP  pkg 0402LF  page 233 : 1 = CLK_100M_BMC_RC_DN_R ; 2 = CLK_100M_BMC_RC_DN
R3337  Q_RES  0 5% CHIP  pkg 0402LF  page 233 : 1 = CLK_100M_GPU_FPGA_DP_R ; 2 = CLK_100M_GPU_FPGA_DP
R3338  Q_RES  0 5% CHIP  pkg 0402LF  page 233 : 1 = CLK_100M_GPU_FPGA_DN_R ; 2 = CLK_100M_GPU_FPGA_DN
R3340  Q_RES  33.2 1% CHIP  pkg 0402LF  page 151 : 1 = SMB_HOST_CLK_3V3AUX_SCL ; 2 = SMB_HOST_CLK_GEN2_3V3AUX_SCL
R3341  Q_RES  33.2 1% CHIP  pkg 0402LF  page 151 : 1 = SMB_HOST_CLK_3V3AUX_SDA ; 2 = SMB_HOST_CLK_GEN2_3V3AUX_SDA
R3352  Q_RES  0 5% CHIP  pkg 0402LF  page 55 : 1 = CLK_100M_CPU1_CLK11_R_DP ; 2 = CLK_100M_CPU1_CLK11_DP
R3353  Q_RES  0 5% CHIP  pkg 0402LF  page 55 : 1 = CLK_100M_CPU1_CLK11_R_DN ; 2 = CLK_100M_CPU1_CLK11_DN
R3354  Q_RES  0 5% CHIP  pkg 0402LF  page 55 : 1 = CLK_100M_CPU1_CLK01_R_DP ; 2 = CLK_100M_CPU1_CLK01_DP
R3355  Q_RES  0 5% CHIP  pkg 0402LF  page 55 : 1 = CLK_100M_CPU1_CLK01_R_DN ; 2 = CLK_100M_CPU1_CLK01_DN
R3390  Q_RES  49.9 1% CHIP  pkg 0402LF  page 128 : 1 = GPU_FPGA_BOOT_EN_BUF_R ; 2 = GPU_FPGA_BOOT_EN_BUF
R3391  Q_RES  49.9 1% CHIP  pkg 0402LF  page 128 : 1 = RST_PERST_2_SWB_BUF_R_N ; 2 = RST_PERST_2_SWB_BUF_N
R3392  Q_RES  49.9 1% CHIP  pkg 0402LF  page 128 : 1 = GPU_BASE_STBY_EN_BUF_R ; 2 = GPU_BASE_STBY_EN_BUF
R3393  Q_RES  0 5% CHIP  pkg 0402LF  page 250 : 1 = SMB_IOEXP_3V3AUX_SCL_R ; 2 = SMB_IOEXP_3V3AUX_SCL
R3394  Q_RES  0 5% CHIP  pkg 0402LF  page 250 : 1 = SMB_IOEXP_3V3AUX_SDA_R ; 2 = SMB_IOEXP_3V3AUX_SDA
R3395  Q_RES  2.2K 5% CHIP  pkg 0402LF  page 250 : 1 = P3V3_AUX ; 2 = SMB_INA230_3V3AUX_SCL
R3396  Q_RES  2.2K 5% CHIP  pkg 0402LF  page 250 : 1 = P3V3_AUX ; 2 = SMB_INA230_3V3AUX_SDA
R3397  Q_RES  33.2 1% CHIP  pkg 0402LF  page 129 : 1 = GPU_NVS_PWR_BRAKE_N_R ; 2 = GPU_NVS_PWR_BRAKE_N_BUF
R3428  Q_RES  100K 1% EMPTY  pkg 0402LF  page 126 : 1 = GPU_FPGA_THERM_OVERT_N ; 2 = GND
R3429  Q_RES  100K 1% EMPTY  pkg 0402LF  page 126 : 1 = P3V3_AUX ; 2 = GPU_BASE_HMC_READY
R3430  Q_RES  100K 1% EMPTY  pkg 0402LF  page 126 : 1 = GPU_FPGA_OVERT_N ; 2 = GND
R3431  Q_RES  100K 1% EMPTY  pkg 0402LF  page 126 : 1 = GPU_HMC_PRSNT_N ; 2 = GND
R3432  Q_RES  4.7K 5% CHIP  pkg 0402LF  page 126 : 1 = P3V3_AUX ; 2 = GPU_FPGA_THERM_OVERT
R3433  Q_RES  4.7K 5% CHIP  pkg 0402LF  page 126 : 1 = P3V3_AUX ; 2 = GPU_BASE_HMC_READY_N
R3434  Q_RES  4.7K 5% CHIP  pkg 0402LF  page 126 : 1 = P3V3_AUX ; 2 = GPU_HMC_PRSNT
R3435  Q_RES  4.7K 5% CHIP  pkg 0402LF  page 126 : 1 = P3V3_AUX ; 2 = GPU_FPGA_OVERT
R3436  Q_RES  100K 1% CHIP  pkg 0402LF  page 126 : 1 = P3V3_AUX ; 2 = GPU_HMC_PRSNT_ISO_N
R3437  Q_RES  100K 1% CHIP  pkg 0402LF  page 126 : 1 = P3V3_AUX ; 2 = GPU_FPGA_OVERT_ISO_N
R3438  Q_RES  100K 1% CHIP  pkg 0402LF  page 126 : 1 = P3V3_AUX ; 2 = GPU_BASE_HMC_READY_ISO
R3439  Q_RES  100K 1% CHIP  pkg 0402LF  page 126 : 1 = P3V3_AUX ; 2 = GPU_FPGA_THERM_OVERT_ISO_N
R3440  Q_RES  0 5% EMPTY  pkg 0402LF  page 123 : 1 = GPU_BASE_ID0 ; 2 = GND
R3441  Q_RES  0 5% CHIP  pkg 0402LF  page 123 : 1 = GPU_BASE_ID1 ; 2 = GND
R3442  Q_RES  0 5% CHIP  pkg 0402LF  page 123 : 1 = GPU_PEX_STRAP0 ; 2 = GND
R3443  Q_RES  0 5% CHIP  pkg 0402LF  page 123 : 1 = GPU_PEX_STRAP1 ; 2 = GND
R3448  Q_RES  4.7K 5% EMPTY  pkg 0402LF  page 128 : 1 = P3V3_AUX ; 2 = GPU_FPGA_BOOT_EN
R3449  Q_RES  100K 1% CHIP  pkg 0402LF  page 128 : 1 = GPU_FPGA_BOOT_EN ; 2 = GND
R3451  Q_RES  4.7K 5% EMPTY  pkg 0402LF  page 128 : 1 = P3V3_AUX ; 2 = GPU_BASE_STBY_EN
R3452  Q_RES  100K 1% CHIP  pkg 0402LF  page 128 : 1 = GPU_BASE_STBY_EN ; 2 = GND
R3453  Q_RES  100K 1% EMPTY  pkg 0402LF  page 128 : 1 = P3V3_AUX ; 2 = GPU_FPGA_BOOT_EN_BUF_R
R3454  Q_RES  1K 1% CHIP  pkg 0402LF  page 128 : 1 = GPU_FPGA_BOOT_EN_BUF_R ; 2 = GND
R3455  Q_RES  10K 1% CHIP  pkg 0402LF  page 128 : 1 = RST_PERST_2_SWB_BUF_R_N ; 2 = GND
R3456  Q_RES  100K 1% EMPTY  pkg 0402LF  page 128 : 1 = P3V3_AUX ; 2 = GPU_BASE_STBY_EN_BUF_R
R3457  Q_RES  10K 1% CHIP  pkg 0402LF  page 128 : 1 = GPU_BASE_STBY_EN_BUF_R ; 2 = GND
R3459  Q_RES  1K 1% CHIP  pkg 0402LF  page 129 : 1 = P3V3_AUX ; 2 = GPU_NVS_PWR_BRAKE_N
R3460  Q_RES  100K 1% EMPTY  pkg 0402LF  page 129 : 1 = GPU_NVS_PWR_BRAKE_N ; 2 = GND
R3461  Q_RES  54.9K 1% CHIP  pkg 0402LF  page 129 : 1 = P3V3_AUX ; 2 = GPU_NVS_PWR_BRAKE_N_R
R3462  Q_RES  100K 1% EMPTY  pkg 0402LF  page 129 : 1 = GPU_NVS_PWR_BRAKE_N_R ; 2 = GND
R3463  Q_RES  54.9K 1% CHIP  pkg 0402LF  page 126 : 1 = GPU_BASE_HMC_READY ; 2 = GND
R3464  Q_RES  54.9K 1% CHIP  pkg 0402LF  page 126 : 1 = P3V3_AUX ; 2 = GPU_FPGA_OVERT_N
R3465  Q_RES  10K 1% CHIP  pkg 0402LF  page 126 : 1 = P3V3_AUX ; 2 = GPU_HMC_PRSNT_N
R3466  Q_RES  10K 1% CHIP  pkg 0402LF  page 128 : 1 = RST_PERST_1_SWB_BUF_R_N ; 2 = GND
R3467  Q_RES  10K 1% CHIP  pkg 0402LF  page 128 : 1 = RST_PERST_0_SWB_BUF_R_N ; 2 = GND
R3468  Q_RES  49.9 1% CHIP  pkg 0402LF  page 128 : 1 = RST_PERST_1_SWB_BUF_R_N ; 2 = RST_PERST_1_SWB_BUF_N
R3469  Q_RES  49.9 1% CHIP  pkg 0402LF  page 128 : 1 = RST_PERST_0_SWB_BUF_R_N ; 2 = RST_PERST_0_SWB_BUF_N
R3470  Q_RES  1K 1% CHIP  pkg 0402LF  page 126 : 1 = P3V3_AUX ; 2 = GPU_WP_HW_CTRL_N
R3471  Q_RES  10K 1% EMPTY  pkg 0402LF  page 126 : 1 = GPU_WP_HW_CTRL_N ; 2 = GND
